# T6G (Grand Teton) — schematic netlist excerpt (pin names and nets, part order shuffled) for the footprints in the layout excerpt that follows; sources: Cadence DE-HDL packaged netlist, KiCad conversion of 04192023_DAF0TMB3IC0_F0TG_MB_C_brd_V02_OCP.brd

R820  Q_RES  10K 5% EMPTY  pkg 0402LF  page 164 : A = UART_VCC_J13 ; B = P5V_AUX
R425  Q_RES  1K 1% EMPTY  pkg 0402LF  page 28 : A = PVDD11_S3_P0 ; B = I3C_0_SPD_DDRAF_CPU0_R_SCL
C7041  Q_CAP  47UF 4V 20% X6S  pkg C0805  page 345 : A = P0V9_CPU1_RT_2D ; B = GND

(kicad_pcb
	(version 20260206)
	(generator "pcbnew")
	(generator_version "10.0")
	(general
		(thickness 1.6)
		(legacy_teardrops no)
	)
	(paper "A4")
	(title_block
		(title "04192023_DAF0TMB3IC0_F0TG_MB_C_brd_V02_OCP.brd")
		(comment 1 "Grand Teton / footprints 1250-1252 of 8354")
	)
	(layers
		(0 "F.Cu" signal "TOP")
		(4 "In1.Cu" signal "GND")
		(6 "In2.Cu" signal "IN1")
		(8 "In3.Cu" signal "GND1")
		(10 "In4.Cu" signal "IN2")
		(12 "In5.Cu" signal "GND2")
		(14 "In6.Cu" signal "IN3")
		(16 "In7.Cu" signal "GND3")
		(18 "In8.Cu" signal "VCC")
		(20 "In9.Cu" signal "VCC1")
		(22 "In10.Cu" signal "GND4")
		(24 "In11.Cu" signal "IN4")
		(26 "In12.Cu" signal "GND5")
		(28 "In13.Cu" signal "IN5")
		(30 "In14.Cu" signal "GND6")
		(32 "In15.Cu" signal "IN6")
		(34 "In16.Cu" signal "GND7")
		(2 "B.Cu" signal "BOTTOM")
		(9 "F.Adhes" user "F.Adhesive")
		(11 "B.Adhes" user "B.Adhesive")
		(13 "F.Paste" user "Package Geometry/Pastemask Top")
		(15 "B.Paste" user "Package Geometry/Pastemask Bottom")
		(5 "F.SilkS" user "Ref Des/Silkscreen Top")
		(7 "B.SilkS" user "Ref Des/Silkscreen Bottom")
		(1 "F.Mask" user "Board Geometry/Soldermask Top")
		(3 "B.Mask" user "Board Geometry/Soldermask Bottom")
		(17 "Dwgs.User" user "User.Drawings")
		(19 "Cmts.User" user "User.Comments")
		(21 "Eco1.User" user "User.Eco1")
		(23 "Eco2.User" user "User.Eco2")
		(25 "Edge.Cuts" user "Board Geometry/Outline")
		(27 "Margin" user)
		(31 "F.CrtYd" user "Package Geometry/Place Bound Top")
		(29 "B.CrtYd" user "Package Geometry/Place Bound Bottom")
		(35 "F.Fab" user "Ref Des/Assembly Top")
		(33 "B.Fab" user "Ref Des/Assembly Bottom")
	)
	(footprint ""
		(layer "F.Cu")
		(at 365.318548 -14.450568 -90)
		(property "Reference" "R820"
			(at 0 0 270)
			(layer "F.SilkS")
			(hide yes)
			(effects
				(font
					(size 1.27 1.27)
				)
			)
		)
		(property "Value" ""
			(at 0 0 270)
			(layer "F.Fab")
			(effects
				(font
					(size 1.27 1.27)
				)
			)
		)
		(duplicate_pad_numbers_are_jumpers no)
		(fp_line
			(start -0.7874 0.4064)
			(end -0.7874 -0.4064)
			(stroke
				(width 0.1524)
				(type default)
			)
			(layer "F.SilkS")
		)
		(fp_line
			(start 0.7874 0.4064)
			(end -0.7874 0.4064)
			(stroke
				(width 0.1524)
				(type default)
			)
			(layer "F.SilkS")
		)
		(fp_line
			(start -0.7874 -0.4064)
			(end 0.7874 -0.4064)
			(stroke
				(width 0.1524)
				(type default)
			)
			(layer "F.SilkS")
		)
		(fp_line
			(start 0.7874 -0.4064)
			(end 0.7874 0.4064)
			(stroke
				(width 0.1524)
				(type default)
			)
			(layer "F.SilkS")
		)
		(fp_line
			(start -0.67945 0.3048)
			(end -0.67945 -0.305054)
			(stroke
				(width 0.1)
				(type default)
			)
			(layer "F.Fab")
		)
		(fp_line
			(start -0.12065 0.3048)
			(end -0.67945 0.3048)
			(stroke
				(width 0.1)
				(type default)
			)
			(layer "F.Fab")
		)
		(fp_line
			(start 0.120396 0.3048)
			(end 0.120396 0.2794)
			(stroke
				(width 0.1)
				(type default)
			)
			(layer "F.Fab")
		)
		(fp_line
			(start 0.67945 0.3048)
			(end 0.120396 0.3048)
			(stroke
				(width 0.1)
				(type default)
			)
			(layer "F.Fab")
		)
		(fp_line
			(start -0.12065 0.2794)
			(end -0.12065 0.3048)
			(stroke
				(width 0.1)
				(type default)
			)
			(layer "F.Fab")
		)
		(fp_line
			(start 0.120396 0.2794)
			(end -0.12065 0.2794)
			(stroke
				(width 0.1)
				(type default)
			)
			(layer "F.Fab")
		)
		(fp_line
			(start -0.12065 -0.2794)
			(end 0.12065 -0.2794)
			(stroke
				(width 0.1)
				(type default)
			)
			(layer "F.Fab")
		)
		(fp_line
			(start 0.12065 -0.2794)
			(end 0.12065 -0.3048)
			(stroke
				(width 0.1)
				(type default)
			)
			(layer "F.Fab")
		)
		(fp_line
			(start 0.12065 -0.3048)
			(end 0.67945 -0.3048)
			(stroke
				(width 0.1)
				(type default)
			)
			(layer "F.Fab")
		)
		(fp_line
			(start 0.67945 -0.3048)
			(end 0.67945 0.3048)
			(stroke
				(width 0.1)
				(type default)
			)
			(layer "F.Fab")
		)
		(fp_line
			(start -0.67945 -0.305054)
			(end -0.12065 -0.305054)
			(stroke
				(width 0.1)
				(type default)
			)
			(layer "F.Fab")
		)
		(fp_line
			(start -0.12065 -0.305054)
			(end -0.12065 -0.2794)
			(stroke
				(width 0.1)
				(type default)
			)
			(layer "F.Fab")
		)
		(pad "1" smd circle
			(at -0.40005 0 270)
			(size 0 0)
			(layers "F.Cu" "F.Mask" "F.Paste")
			(net "UART_VCC_J13")
		)
		(pad "2" smd circle
			(at 0.40005 0 270)
			(size 0 0)
			(layers "F.Cu" "F.Mask" "F.Paste")
			(net "P5V_AUX")
		)
	)
	(footprint ""
		(layer "F.Cu")
		(at 50.254662 -401.98294 90)
		(property "Reference" "C7041"
			(at 0 0 90)
			(layer "F.SilkS")
			(hide yes)
			(effects
				(font
					(size 1.27 1.27)
				)
			)
		)
		(property "Value" ""
			(at 0 0 90)
			(layer "F.Fab")
			(effects
				(font
					(size 1.27 1.27)
				)
			)
		)
		(duplicate_pad_numbers_are_jumpers no)
		(fp_line
			(start 1.524 -0.762)
			(end 1.524 0.762)
			(stroke
				(width 0.1524)
				(type default)
			)
			(layer "F.SilkS")
		)
		(fp_line
			(start -1.524 -0.762)
			(end 1.524 -0.762)
			(stroke
				(width 0.1524)
				(type default)
			)
			(layer "F.SilkS")
		)
		(fp_line
			(start 1.524 0.762)
			(end -1.524 0.762)
			(stroke
				(width 0.1524)
				(type default)
			)
			(layer "F.SilkS")
		)
		(fp_line
			(start -1.524 0.762)
			(end -1.524 -0.762)
			(stroke
				(width 0.1524)
				(type default)
			)
			(layer "F.SilkS")
		)
		(fp_line
			(start 1.1049 -0.724916)
			(end -1.1049 -0.724916)
			(stroke
				(width 0.1)
				(type default)
			)
			(layer "F.Fab")
		)
		(fp_line
			(start -1.1049 -0.724916)
			(end -1.1049 0.724916)
			(stroke
				(width 0.1)
				(type default)
			)
			(layer "F.Fab")
		)
		(fp_line
			(start 1.1049 0.724916)
			(end 1.1049 -0.724916)
			(stroke
				(width 0.1)
				(type default)
			)
			(layer "F.Fab")
		)
		(fp_line
			(start -1.1049 0.724916)
			(end 1.1049 0.724916)
			(stroke
				(width 0.1)
				(type default)
			)
			(layer "F.Fab")
		)
		(pad "1" smd rect
			(at -0.889 0 270)
			(size 1.016 1.27)
			(layers "F.Cu" "F.Mask" "F.Paste")
			(net "P0V9_CPU1_RT_2D")
		)
		(pad "2" smd rect
			(at 0.889 0 270)
			(size 1.016 1.27)
			(layers "F.Cu" "F.Mask" "F.Paste")
			(net "GND")
		)
	)
	(footprint ""
		(layer "F.Cu")
		(at 321.183 -194.31 180)
		(property "Reference" "R425"
			(at 0 0 180)
			(layer "F.SilkS")
			(hide yes)
			(effects
				(font
					(size 1.27 1.27)
				)
			)
		)
		(property "Value" ""
			(at 0 0 180)
			(layer "F.Fab")
			(effects
				(font
					(size 1.27 1.27)
				)
			)
		)
		(duplicate_pad_numbers_are_jumpers no)
		(fp_line
			(start 0.7874 0.4064)
			(end -0.7874 0.4064)
			(stroke
				(width 0.1524)
				(type default)
			)
			(layer "F.SilkS")
		)
		(fp_line
			(start 0.7874 -0.4064)
			(end 0.7874 0.4064)
			(stroke
				(width 0.1524)
				(type default)
			)
			(layer "F.SilkS")
		)
		(fp_line
			(start -0.7874 0.4064)
			(end -0.7874 -0.4064)
			(stroke
				(width 0.1524)
				(type default)
			)
			(layer "F.SilkS")
		)
		(fp_line
			(start -0.7874 -0.4064)
			(end 0.7874 -0.4064)
			(stroke
				(width 0.1524)
				(type default)
			)
			(layer "F.SilkS")
		)
		(fp_line
			(start 0.67945 0.3048)
			(end 0.120396 0.3048)
			(stroke
				(width 0.1)
				(type default)
			)
			(layer "F.Fab")
		)
		(fp_line
			(start 0.67945 -0.3048)
			(end 0.67945 0.3048)
			(stroke
				(width 0.1)
				(type default)
			)
			(layer "F.Fab")
		)
		(fp_line
			(start 0.12065 -0.2794)
			(end 0.12065 -0.3048)
			(stroke
				(width 0.1)
				(type default)
			)
			(layer "F.Fab")
		)
		(fp_line
			(start 0.12065 -0.3048)
			(end 0.67945 -0.3048)
			(stroke
				(width 0.1)
				(type default)
			)
			(layer "F.Fab")
		)
		(fp_line
			(start 0.120396 0.3048)
			(end 0.120396 0.2794)
			(stroke
				(width 0.1)
				(type default)
			)
			(layer "F.Fab")
		)
		(fp_line
			(start 0.120396 0.2794)
			(end -0.12065 0.2794)
			(stroke
				(width 0.1)
				(type default)
			)
			(layer "F.Fab")
		)
		(fp_line
			(start -0.12065 0.3048)
			(end -0.67945 0.3048)
			(stroke
				(width 0.1)
				(type default)
			)
			(layer "F.Fab")
		)
		(fp_line
			(start -0.12065 0.2794)
			(end -0.12065 0.3048)
			(stroke
				(width 0.1)
				(type default)
			)
			(layer "F.Fab")
		)
		(fp_line
			(start -0.12065 -0.2794)
			(end 0.12065 -0.2794)
			(stroke
				(width 0.1)
				(type default)
			)
			(layer "F.Fab")
		)
		(fp_line
			(start -0.12065 -0.305054)
			(end -0.12065 -0.2794)
			(stroke
				(width 0.1)
				(type default)
			)
			(layer "F.Fab")
		)
		(fp_line
			(start -0.67945 0.3048)
			(end -0.67945 -0.305054)
			(stroke
				(width 0.1)
				(type default)
			)
			(layer "F.Fab")
		)
		(fp_line
			(start -0.67945 -0.305054)
			(end -0.12065 -0.305054)
			(stroke
				(width 0.1)
				(type default)
			)
			(layer "F.Fab")
		)
		(pad "1" smd circle
			(at -0.40005 0 180)
			(size 0 0)
			(layers "F.Cu" "F.Mask" "F.Paste")
			(net "PVDD11_S3_P0")
		)
		(pad "2" smd circle
			(at 0.40005 0 180)
			(size 0 0)
			(layers "F.Cu" "F.Mask" "F.Paste")
			(net "I3C_0_SPD_DDRAF_CPU0_R_SCL")
		)
	)
)
